FILE_TYPE = MACRO_DRAWING;
SET COLOR_WIRE YELLOW;
SET COLOR_PROP MONO;
SET COLOR_DOT WHITE;
SET COLOR_ARC YELLOW;
SET COLOR_BODY GREEN;
SET COLOR_NOTE MONO;
SET PROP_DISPLAY VALUE;
SET PAGE_NUMBER P166;
FORCEADD OFFPAGE..3
R 2
(-5750 3125);
FORCEPROP 2 LAST $XR0 145 
J 0
(-6060 3125);
DISPLAY 0.638298 (-6060 3125);
PAINT MONO (-6060 3125);
FORCEPROP 1 LAST COMMENT_BODY TRUE
J 2
(-5700 3025);
DISPLAY 0.978723 (-5700 3025);
PAINT GREEN (-5700 3025);
DISPLAY INVISIBLE (-5700 3025);
FORCEPROP 1 LAST OFFPAGE TRUE
J 2
(-6075 3000);
PAINT GREEN (-6075 3000);
DISPLAY INVISIBLE (-6075 3000);
FORCEPROP 2 LAST PATH I16
J 0
(-5690 3200);
DISPLAY 1.361702 (-5690 3200);
PAINT ORANGE (-5690 3200);
DISPLAY INVISIBLE (-5690 3200);
FORCEPROP 2 LAST CDS_LIB mstr_standard
J 0
(-5750 3125);
DISPLAY 1.531915 (-5750 3125);
PAINT ORANGE (-5750 3125);
DISPLAY INVISIBLE (-5750 3125);
FORCEADD OFFPAGE..3
R 2
(-5750 2525);
FORCEPROP 2 LAST $XR0 118 
J 0
(-6060 2525);
DISPLAY 0.638298 (-6060 2525);
PAINT MONO (-6060 2525);
FORCEPROP 1 LAST OFFPAGE TRUE
J 2
(-6075 2400);
PAINT GREEN (-6075 2400);
DISPLAY INVISIBLE (-6075 2400);
FORCEPROP 1 LAST COMMENT_BODY TRUE
J 2
(-5700 2425);
DISPLAY 0.978723 (-5700 2425);
PAINT GREEN (-5700 2425);
DISPLAY INVISIBLE (-5700 2425);
FORCEPROP 2 LAST CDS_LIB mstr_standard
J 0
(-5750 2525);
DISPLAY 1.531915 (-5750 2525);
PAINT ORANGE (-5750 2525);
DISPLAY INVISIBLE (-5750 2525);
FORCEPROP 2 LAST PATH I17
J 0
(-5690 2600);
DISPLAY 1.361702 (-5690 2600);
PAINT ORANGE (-5690 2600);
DISPLAY INVISIBLE (-5690 2600);
FORCEADD RES..2
R 2
(-5050 3500);
FORCEPROP 1 LAST TOLERANCE 1%
J 2
(-5095 3525);
DISPLAY 0.617021 (-5095 3525);
PAINT SKYBLUE (-5095 3525);
FORCEPROP 1 LAST MATERIAL CHIP
J 2
(-5090 3425);
DISPLAY 0.617021 (-5090 3425);
PAINT SKYBLUE (-5090 3425);
FORCEPROP 1 LAST PACK_TYPE 0402
J 2
(-5090 3325);
DISPLAY 0.617021 (-5090 3325);
PAINT SKYBLUE (-5090 3325);
FORCEPROP 1 LAST PART_NUMBER G21796-072
J 2
(-5090 3375);
DISPLAY 0.617021 (-5090 3375);
PAINT BLUE (-5090 3375);
FORCEPROP 1 LAST VALUE 4.75K
J 2
(-5095 3575);
DISPLAY 0.617021 (-5095 3575);
PAINT SKYBLUE (-5095 3575);
FORCEPROP 1 LASTPIN (-5050 3600) $PN 1
J 2
(-5055 3562);
DISPLAY 0.617021 (-5055 3562);
PAINT MONO (-5055 3562);
FORCEPROP 1 LASTPIN (-5050 3400) $PN 2
J 2
(-5055 3410);
DISPLAY 0.617021 (-5055 3410);
PAINT MONO (-5055 3410);
FORCEPROP 1 LAST WATTAGE 1/16W
J 2
(-5090 3475);
DISPLAY 0.617021 (-5090 3475);
PAINT SKYBLUE (-5090 3475);
FORCEPROP 1 LAST LOCATION R7C17
J 2
(-5095 3625);
DISPLAY 0.617021 (-5095 3625);
PAINT AQUA (-5095 3625);
FORCEPROP 2 LAST CDS_LIB mstr_discrete
J 2
(-5050 3500);
DISPLAY 1.531915 (-5050 3500);
PAINT ORANGE (-5050 3500);
DISPLAY INVISIBLE (-5050 3500);
FORCEPROP 2 LAST ROOM PECI
J 0
(-5075 3675);
DISPLAY 1.021277 (-5075 3675);
PAINT ORANGE (-5075 3675);
DISPLAY INVISIBLE (-5075 3675);
FORCEPROP 1 LAST PATH I28
J 2
(-5100 3675);
DISPLAY 1.319149 (-5100 3675);
PAINT GREEN (-5100 3675);
DISPLAY INVISIBLE (-5100 3675);
FORCEPROP 2 LAST CDS_LOCATION R7C17
J 2
(-5095 3625);
DISPLAY 0.617021 (-5095 3625);
PAINT AQUA (-5095 3625);
DISPLAY INVISIBLE (-5095 3625);
FORCEPROP 2 LAST SEC 1
J 0
(-5100 3725);
DISPLAY 0.936170 (-5100 3725);
PAINT MONO (-5100 3725);
DISPLAY INVISIBLE (-5100 3725);
FORCEPROP 2 LAST SEC_TYPE 0402
J 0
(-5100 3725);
PAINT MONO (-5100 3725);
DISPLAY INVISIBLE (-5100 3725);
FORCEPROP 2 LAST BOM_COST DEBUG
J 0
(-5075 3725);
DISPLAY 1.021277 (-5075 3725);
PAINT ORANGE (-5075 3725);
DISPLAY INVISIBLE (-5075 3725);
FORCEADD PVCCIO_CPU0..1
(-5050 3775);
FORCEPROP 3 LASTPIN (-5050 3725) SIG_NAME PVCCIO_CPU0\g
J 0
(-5040 3735);
DISPLAY 0.659574 (-5040 3735);
PAINT MONO (-5040 3735);
DISPLAY INVISIBLE (-5040 3735);
FORCEPROP 2 LAST CDS_LIB mstr_symbols
J 0
(-5050 3775);
PAINT ORANGE (-5050 3775);
DISPLAY INVISIBLE (-5050 3775);
FORCEPROP 1 LAST PATH I31
J 0
(-5000 3800);
DISPLAY 0.872340 (-5000 3800);
PAINT AQUA (-5000 3800);
DISPLAY INVISIBLE (-5000 3800);
FORCEPROP 1 LAST HDL_POWER PVCCIO_CPU0
J 1
(-5050 3825);
DISPLAY 0.872340 (-5050 3825);
PAINT GREEN (-5050 3825);
DISPLAY INVISIBLE (-5050 3825);
FORCEPROP 1 LAST BODY_TYPE PLUMBING
J 0
(-5095 3732);
DISPLAY 0.340426 (-5095 3732);
PAINT GREEN (-5095 3732);
DISPLAY INVISIBLE (-5095 3732);
FORCEPROP 1 LAST VOLTAGE 1.1V
J 0
(-5095 3732);
DISPLAY 0.340426 (-5095 3732);
PAINT SKYBLUE (-5095 3732);
DISPLAY INVISIBLE (-5095 3732);
FORCEADD RES..2
(-4475 2150);
FORCEPROP 1 LAST LOCATION R7D15
J 0
(-4430 2275);
DISPLAY 0.617021 (-4430 2275);
PAINT AQUA (-4430 2275);
FORCEPROP 1 LAST VALUE 348
J 0
(-4430 2225);
DISPLAY 0.617021 (-4430 2225);
PAINT SKYBLUE (-4430 2225);
FORCEPROP 1 LASTPIN (-4475 2050) $PN 2
J 0
(-4470 2060);
DISPLAY 0.617021 (-4470 2060);
PAINT ORANGE (-4470 2060);
FORCEPROP 1 LASTPIN (-4475 2250) $PN 1
J 0
(-4470 2212);
DISPLAY 0.617021 (-4470 2212);
PAINT ORANGE (-4470 2212);
FORCEPROP 1 LAST TOLERANCE 1%
J 0
(-4430 2175);
DISPLAY 0.617021 (-4430 2175);
PAINT SKYBLUE (-4430 2175);
FORCEPROP 1 LAST WATTAGE 1/16W
J 0
(-4435 2125);
DISPLAY 0.617021 (-4435 2125);
PAINT SKYBLUE (-4435 2125);
FORCEPROP 1 LAST MATERIAL CHIP
J 0
(-4435 2075);
DISPLAY 0.617021 (-4435 2075);
PAINT SKYBLUE (-4435 2075);
FORCEPROP 1 LAST PART_NUMBER G21796-340
J 0
(-4435 2025);
DISPLAY 0.617021 (-4435 2025);
PAINT BLUE (-4435 2025);
FORCEPROP 1 LAST PACK_TYPE 0402
J 0
(-4435 1975);
DISPLAY 0.617021 (-4435 1975);
PAINT SKYBLUE (-4435 1975);
FORCEPROP 0 LAST BOM_COST DEBUG
J 0
(-4425 2475);
DISPLAY 1.021277 (-4425 2475);
PAINT ORANGE (-4425 2475);
DISPLAY INVISIBLE (-4425 2475);
FORCEPROP 2 LAST SEC_TYPE 0402
J 0
(-4425 2375);
DISPLAY 1.021277 (-4425 2375);
PAINT ORANGE (-4425 2375);
DISPLAY INVISIBLE (-4425 2375);
FORCEPROP 2 LAST SEC 1
J 0
(-4425 2375);
DISPLAY 0.680851 (-4425 2375);
PAINT MONO (-4425 2375);
DISPLAY INVISIBLE (-4425 2375);
FORCEPROP 2 LAST CDS_LOCATION R7D15
J 0
(-4430 2275);
DISPLAY 0.617021 (-4430 2275);
PAINT AQUA (-4430 2275);
DISPLAY INVISIBLE (-4430 2275);
FORCEPROP 1 LAST PATH I32
J 0
(-4425 2325);
DISPLAY 0.978723 (-4425 2325);
PAINT WHITE (-4425 2325);
DISPLAY INVISIBLE (-4425 2325);
FORCEPROP 0 LAST ROOM PECI
J 0
(-4425 2375);
DISPLAY 1.021277 (-4425 2375);
PAINT ORANGE (-4425 2375);
DISPLAY INVISIBLE (-4425 2375);
FORCEPROP 2 LAST CDS_LIB mstr_discrete
J 0
(-4475 2150);
PAINT ORANGE (-4475 2150);
DISPLAY INVISIBLE (-4475 2150);
FORCEADD GND..1
(-4475 1900);
FORCEPROP 3 LASTPIN (-4475 1950) SIG_NAME GND\g
J 0
(-4465 1960);
DISPLAY 0.659574 (-4465 1960);
PAINT MONO (-4465 1960);
DISPLAY INVISIBLE (-4465 1960);
FORCEPROP 1 LAST PATH I33
J 0
(-4400 1900);
DISPLAY 0.872340 (-4400 1900);
PAINT AQUA (-4400 1900);
DISPLAY INVISIBLE (-4400 1900);
FORCEPROP 1 LAST BODY_TYPE PLUMBING
J 0
(-4520 1857);
DISPLAY 0.340426 (-4520 1857);
PAINT GREEN (-4520 1857);
DISPLAY INVISIBLE (-4520 1857);
FORCEPROP 1 LAST SIZE 1B
J 0
(-4400 1850);
DISPLAY 0.872340 (-4400 1850);
PAINT AQUA (-4400 1850);
DISPLAY INVISIBLE (-4400 1850);
FORCEPROP 2 LAST CDS_LIB mstr_symbols
J 0
(-4475 1900);
PAINT ORANGE (-4475 1900);
DISPLAY INVISIBLE (-4475 1900);
FORCEPROP 1 LAST VOLTAGE 0.0V
J 0
(-4520 1857);
DISPLAY 0.340426 (-4520 1857);
PAINT SKYBLUE (-4520 1857);
DISPLAY INVISIBLE (-4520 1857);
FORCEPROP 1 LAST HDL_POWER GND
J 0
(-4475 2050);
DISPLAY 0.872340 (-4475 2050);
PAINT GREEN (-4475 2050);
DISPLAY INVISIBLE (-4475 2050);
FORCEADD PI5A3157BC6E-GP..1
(-3400 2825);
FORCEPROP 1 LAST LOCATION U7W1
J 0
(-3550 3000);
DISPLAY 0.617021 (-3550 3000);
PAINT GREEN (-3550 3000);
FORCEPROP 2 LASTPIN (-3100 2925) $PN 6
J 0
(-3090 2935);
DISPLAY 0.808511 (-3090 2935);
PAINT ORANGE (-3090 2935);
FORCEPROP 2 LASTPIN (-3100 2825) $PN 5
J 0
(-3090 2835);
DISPLAY 0.808511 (-3090 2835);
PAINT ORANGE (-3090 2835);
FORCEPROP 2 LASTPIN (-3700 2925) $PN 1
J 2
(-3710 2935);
DISPLAY 0.808511 (-3710 2935);
PAINT ORANGE (-3710 2935);
FORCEPROP 2 LASTPIN (-3700 2725) $PN 3
J 2
(-3710 2735);
DISPLAY 0.808511 (-3710 2735);
PAINT ORANGE (-3710 2735);
FORCEPROP 2 LASTPIN (-3100 2725) $PN 4
J 0
(-3090 2735);
DISPLAY 0.808511 (-3090 2735);
PAINT ORANGE (-3090 2735);
FORCEPROP 2 LASTPIN (-3700 2825) $PN 2
J 2
(-3710 2835);
DISPLAY 0.808511 (-3710 2835);
PAINT ORANGE (-3710 2835);
FORCEPROP 1 LAST VALUE PI5A3157BC6E-GP
J 0
(-3550 2625);
DISPLAY 0.617021 (-3550 2625);
PAINT GREEN (-3550 2625);
FORCEPROP 2 LAST SEC_TYPE DISCRET-GC2
J 0
(-3550 3050);
DISPLAY 1.021277 (-3550 3050);
PAINT ORANGE (-3550 3050);
DISPLAY INVISIBLE (-3550 3050);
FORCEPROP 2 LAST SEC 1
J 0
(-3550 3050);
DISPLAY 0.680851 (-3550 3050);
PAINT MONO (-3550 3050);
DISPLAY INVISIBLE (-3550 3050);
FORCEPROP 1 LAST PACK_TYPE DISCRET-GC2
J 0
(-3400 2825);
DISPLAY 0.617021 (-3400 2825);
PAINT GREEN (-3400 2825);
DISPLAY INVISIBLE (-3400 2825);
FORCEPROP 1 LAST PART_NUMBER 073.53157.000J
J 0
(-3400 2785);
DISPLAY 0.617021 (-3400 2785);
PAINT GREEN (-3400 2785);
DISPLAY INVISIBLE (-3400 2785);
FORCEPROP 2 LAST CDS_LIB w_hdl
J 0
(-3400 2825);
PAINT MONO (-3400 2825);
DISPLAY INVISIBLE (-3400 2825);
FORCEPROP 1 LAST PATH I34
J 0
(-3400 2865);
DISPLAY 0.617021 (-3400 2865);
PAINT GREEN (-3400 2865);
DISPLAY INVISIBLE (-3400 2865);
FORCEPROP 1 LAST CDS_LMAN_SYM_OUTLINE -150,150,150,-150
J 0
(-3400 2825);
DISPLAY 0.468085 (-3400 2825);
PAINT GREEN (-3400 2825);
DISPLAY INVISIBLE (-3400 2825);
FORCEADD CAP_A..1
(-2725 3225);
FORCEPROP 1 LAST VOLTAGE 16V
J 0
(-2675 3225);
DISPLAY 0.617021 (-2675 3225);
PAINT SKYBLUE (-2675 3225);
FORCEPROP 1 LAST TOLERANCE 10%
J 0
(-2675 3175);
DISPLAY 0.617021 (-2675 3175);
PAINT SKYBLUE (-2675 3175);
FORCEPROP 1 LAST MATERIAL X7R
J 0
(-2675 3125);
DISPLAY 0.617021 (-2675 3125);
PAINT SKYBLUE (-2675 3125);
FORCEPROP 1 LASTPIN (-2725 3325) $PN 1
J 0
(-2715 3305);
DISPLAY 0.617021 (-2715 3305);
PAINT MONO (-2715 3305);
FORCEPROP 1 LASTPIN (-2725 3125) $PN 2
J 0
(-2715 3105);
DISPLAY 0.617021 (-2715 3105);
PAINT MONO (-2715 3105);
FORCEPROP 1 LAST LOCATION C7W1
J 0
(-2675 3325);
DISPLAY 0.617021 (-2675 3325);
PAINT AQUA (-2675 3325);
FORCEPROP 1 LAST VALUE 0.1UF
J 0
(-2675 3275);
DISPLAY 0.617021 (-2675 3275);
PAINT SKYBLUE (-2675 3275);
FORCEPROP 1 LAST PART_NUMBER A36096-030
J 0
(-2675 3075);
DISPLAY 0.617021 (-2675 3075);
PAINT BLUE (-2675 3075);
FORCEPROP 1 LAST PACK_TYPE 0402V
J 0
(-2675 3025);
DISPLAY 0.617021 (-2675 3025);
PAINT SKYBLUE (-2675 3025);
FORCEPROP 2 LAST ROOM PROC_SIDEBAND
J 0
(-2675 2975);
DISPLAY 0.978723 (-2675 2975);
PAINT ORANGE (-2675 2975);
DISPLAY INVISIBLE (-2675 2975);
FORCEPROP 2 LAST BOM_COST PROC_SIDEBAND
J 0
(-2725 3225);
PAINT MONO (-2725 3225);
DISPLAY INVISIBLE (-2725 3225);
FORCEPROP 2 LAST CDS_LIB dev_discrete
J 0
(-2725 3225);
PAINT ORANGE (-2725 3225);
DISPLAY INVISIBLE (-2725 3225);
FORCEPROP 2 LAST CDS_SEC 1
J 0
(-2675 3375);
PAINT ORANGE (-2675 3375);
DISPLAY INVISIBLE (-2675 3375);
FORCEPROP 2 LAST SEC_TYPE 0402V
J 0
(-2675 3425);
PAINT MONO (-2675 3425);
DISPLAY INVISIBLE (-2675 3425);
FORCEPROP 2 LAST SEC 1
J 0
(-2675 3425);
DISPLAY 0.936170 (-2675 3425);
PAINT MONO (-2675 3425);
DISPLAY INVISIBLE (-2675 3425);
FORCEPROP 1 LAST PATH I36
J 0
(-2675 3375);
DISPLAY 0.978723 (-2675 3375);
PAINT WHITE (-2675 3375);
DISPLAY INVISIBLE (-2675 3375);
FORCEPROP 2 LAST CDS_LOCATION C7W1
J 0
(-2675 3325);
DISPLAY 0.617021 (-2675 3325);
PAINT AQUA (-2675 3325);
DISPLAY INVISIBLE (-2675 3325);
FORCEADD GND..1
(-2725 3025);
FORCEPROP 3 LASTPIN (-2725 3075) SIG_NAME GND\g
J 0
(-2715 3085);
DISPLAY 0.659574 (-2715 3085);
PAINT MONO (-2715 3085);
DISPLAY INVISIBLE (-2715 3085);
FORCEPROP 1 LAST HDL_POWER GND
J 0
(-2725 3175);
DISPLAY 0.872340 (-2725 3175);
PAINT GREEN (-2725 3175);
DISPLAY INVISIBLE (-2725 3175);
FORCEPROP 1 LAST VOLTAGE 0.0V
J 0
(-2770 2982);
DISPLAY 0.340426 (-2770 2982);
PAINT SKYBLUE (-2770 2982);
DISPLAY INVISIBLE (-2770 2982);
FORCEPROP 2 LAST CDS_LIB mstr_symbols
J 0
(-2725 3025);
PAINT ORANGE (-2725 3025);
DISPLAY INVISIBLE (-2725 3025);
FORCEPROP 1 LAST SIZE 1B
J 0
(-2650 2975);
DISPLAY 0.872340 (-2650 2975);
PAINT AQUA (-2650 2975);
DISPLAY INVISIBLE (-2650 2975);
FORCEPROP 1 LAST BODY_TYPE PLUMBING
J 0
(-2770 2982);
DISPLAY 0.340426 (-2770 2982);
PAINT GREEN (-2770 2982);
DISPLAY INVISIBLE (-2770 2982);
FORCEPROP 1 LAST PATH I37
J 0
(-2650 3025);
DISPLAY 0.872340 (-2650 3025);
PAINT AQUA (-2650 3025);
DISPLAY INVISIBLE (-2650 3025);
FORCEADD OFFPAGE..1
R 2
(-2125 2925);
FORCEPROP 2 LAST $XR0 146 
J 0
(-1939 2925);
DISPLAY 0.638298 (-1939 2925);
PAINT MONO (-1939 2925);
FORCEPROP 1 LAST OFFPAGE TRUE
J 2
(-2450 2800);
DISPLAY 0.872340 (-2450 2800);
PAINT GREEN (-2450 2800);
DISPLAY INVISIBLE (-2450 2800);
FORCEPROP 1 LAST COMMENT_BODY TRUE
J 2
(-2250 2825);
DISPLAY 0.872340 (-2250 2825);
PAINT GREEN (-2250 2825);
DISPLAY INVISIBLE (-2250 2825);
FORCEPROP 2 LAST PATH I38
J 0
(-1950 3000);
DISPLAY 1.021277 (-1950 3000);
PAINT ORANGE (-1950 3000);
DISPLAY INVISIBLE (-1950 3000);
FORCEPROP 2 LAST CDS_LIB mstr_standard
J 0
(-2125 2925);
PAINT MONO (-2125 2925);
DISPLAY INVISIBLE (-2125 2925);
FORCEADD OFFPAGE..3
(-2125 2725);
FORCEPROP 2 LAST $XR1 55 
J 0
(-1821 2725);
DISPLAY 0.638298 (-1821 2725);
PAINT MONO (-1821 2725);
FORCEPROP 2 LAST $XR0 21 
J 0
(-1911 2725);
DISPLAY 0.638298 (-1911 2725);
PAINT MONO (-1911 2725);
FORCEPROP 1 LAST OFFPAGE TRUE
J 0
(-1800 2600);
DISPLAY 1.170213 (-1800 2600);
PAINT GREEN (-1800 2600);
DISPLAY INVISIBLE (-1800 2600);
FORCEPROP 1 LAST COMMENT_BODY TRUE
J 0
(-2175 2625);
DISPLAY 1.170213 (-2175 2625);
PAINT PEACH (-2175 2625);
DISPLAY INVISIBLE (-2175 2625);
FORCEPROP 2 LAST PATH I39
J 0
(-1925 2800);
DISPLAY 1.021277 (-1925 2800);
PAINT ORANGE (-1925 2800);
DISPLAY INVISIBLE (-1925 2800);
FORCEPROP 2 LAST CDS_LIB mstr_standard
J 0
(-2125 2725);
PAINT MONO (-2125 2725);
DISPLAY INVISIBLE (-2125 2725);
FORCEADD P3V3_STBY..1
(-2875 3475);
FORCEPROP 3 LASTPIN (-2875 3425) SIG_NAME P3V3_STBY\g
J 0
(-2865 3435);
DISPLAY 0.659574 (-2865 3435);
PAINT MONO (-2865 3435);
DISPLAY INVISIBLE (-2865 3435);
FORCEPROP 1 LAST SIZE 1B
J 0
(-2830 3497);
DISPLAY 0.340426 (-2830 3497);
PAINT GREEN (-2830 3497);
DISPLAY INVISIBLE (-2830 3497);
FORCEPROP 1 LAST VOLTAGE 3.3V
J 0
(-2920 3432);
DISPLAY 0.340426 (-2920 3432);
PAINT SKYBLUE (-2920 3432);
DISPLAY INVISIBLE (-2920 3432);
FORCEPROP 1 LAST BODY_TYPE PLUMBING
J 0
(-2920 3432);
DISPLAY 0.340426 (-2920 3432);
PAINT GREEN (-2920 3432);
DISPLAY INVISIBLE (-2920 3432);
FORCEPROP 1 LAST HDL_POWER P3V3_STBY
J 0
(-3175 3350);
DISPLAY 0.872340 (-3175 3350);
PAINT ORANGE (-3175 3350);
DISPLAY INVISIBLE (-3175 3350);
FORCEPROP 1 LAST PATH I40
J 0
(-2830 3477);
DISPLAY 0.340426 (-2830 3477);
PAINT GREEN (-2830 3477);
DISPLAY INVISIBLE (-2830 3477);
FORCEPROP 2 LAST CDS_LIB mstr_symbols
J 0
(-2875 3475);
PAINT ORANGE (-2875 3475);
DISPLAY INVISIBLE (-2875 3475);
FORCEADD GND..1
R 5
(-3850 2825);
FORCEPROP 3 LASTPIN (-3800 2825) SIG_NAME GND\g
J 0
(-3790 2835);
DISPLAY 0.659574 (-3790 2835);
PAINT MONO (-3790 2835);
DISPLAY INVISIBLE (-3790 2835);
FORCEPROP 1 LAST HDL_POWER GND
R 3
J 0
(-3700 2825);
DISPLAY 0.872340 (-3700 2825);
PAINT GREEN (-3700 2825);
DISPLAY INVISIBLE (-3700 2825);
FORCEPROP 1 LAST VOLTAGE 0.0V
R 3
J 0
(-3893 2870);
DISPLAY 0.340426 (-3893 2870);
PAINT SKYBLUE (-3893 2870);
DISPLAY INVISIBLE (-3893 2870);
FORCEPROP 2 LAST CDS_LIB mstr_symbols
R 3
J 0
(-3850 2825);
PAINT ORANGE (-3850 2825);
DISPLAY INVISIBLE (-3850 2825);
FORCEPROP 1 LAST SIZE 1B
R 3
J 0
(-3900 2750);
DISPLAY 0.872340 (-3900 2750);
PAINT AQUA (-3900 2750);
DISPLAY INVISIBLE (-3900 2750);
FORCEPROP 1 LAST BODY_TYPE PLUMBING
R 3
J 0
(-3893 2870);
DISPLAY 0.340426 (-3893 2870);
PAINT GREEN (-3893 2870);
DISPLAY INVISIBLE (-3893 2870);
FORCEPROP 1 LAST PATH I41
R 3
J 0
(-3850 2750);
DISPLAY 0.872340 (-3850 2750);
PAINT AQUA (-3850 2750);
DISPLAY INVISIBLE (-3850 2750);
FORCEADD RES..2
(-2400 2500);
FORCEPROP 1 LAST LOCATION R7W2
J 0
(-2355 2625);
DISPLAY 0.617021 (-2355 2625);
PAINT AQUA (-2355 2625);
FORCEPROP 1 LASTPIN (-2400 2600) $PN 1
J 0
(-2395 2562);
DISPLAY 0.617021 (-2395 2562);
PAINT ORANGE (-2395 2562);
FORCEPROP 1 LASTPIN (-2400 2400) $PN 2
J 0
(-2395 2410);
DISPLAY 0.617021 (-2395 2410);
PAINT ORANGE (-2395 2410);
FORCEPROP 1 LAST PACK_TYPE 0402
J 0
(-2360 2325);
DISPLAY 0.617021 (-2360 2325);
PAINT SKYBLUE (-2360 2325);
FORCEPROP 1 LAST PART_NUMBER G21796-016
J 0
(-2360 2375);
DISPLAY 0.617021 (-2360 2375);
PAINT BLUE (-2360 2375);
FORCEPROP 1 LAST MATERIAL EMPTY
J 0
(-2360 2425);
DISPLAY 0.617021 (-2360 2425);
PAINT RED (-2360 2425);
FORCEPROP 1 LAST WATTAGE 1/16W
J 0
(-2360 2475);
DISPLAY 0.617021 (-2360 2475);
PAINT SKYBLUE (-2360 2475);
FORCEPROP 1 LAST TOLERANCE 1%
J 0
(-2355 2525);
DISPLAY 0.617021 (-2355 2525);
PAINT SKYBLUE (-2355 2525);
FORCEPROP 1 LAST VALUE 10.0K
J 0
(-2355 2575);
DISPLAY 0.617021 (-2355 2575);
PAINT SKYBLUE (-2355 2575);
FORCEPROP 2 LAST CDS_LIB mstr_discrete
J 0
(-2400 2500);
PAINT ORANGE (-2400 2500);
DISPLAY INVISIBLE (-2400 2500);
FORCEPROP 2 LAST BOM_COST SYS_CLOCK
J 0
(-2350 2825);
DISPLAY 1.021277 (-2350 2825);
PAINT ORANGE (-2350 2825);
DISPLAY INVISIBLE (-2350 2825);
FORCEPROP 2 LAST SEC_TYPE 0402
J 0
(-2350 2725);
DISPLAY 1.021277 (-2350 2725);
PAINT ORANGE (-2350 2725);
DISPLAY INVISIBLE (-2350 2725);
FORCEPROP 2 LAST SEC 1
J 0
(-2350 2725);
DISPLAY 0.680851 (-2350 2725);
PAINT MONO (-2350 2725);
DISPLAY INVISIBLE (-2350 2725);
FORCEPROP 2 LAST ROOM DB1200ZL
J 0
(-2350 2725);
DISPLAY 1.021277 (-2350 2725);
PAINT ORANGE (-2350 2725);
DISPLAY INVISIBLE (-2350 2725);
FORCEPROP 1 LAST PATH I42
J 0
(-2350 2675);
DISPLAY 0.978723 (-2350 2675);
PAINT WHITE (-2350 2675);
DISPLAY INVISIBLE (-2350 2675);
FORCEPROP 2 LAST CDS_LOCATION R7W2
J 0
(-2355 2625);
DISPLAY 0.617021 (-2355 2625);
PAINT AQUA (-2355 2625);
DISPLAY INVISIBLE (-2355 2625);
FORCEADD GND..1
(-2400 2250);
FORCEPROP 3 LASTPIN (-2400 2300) SIG_NAME GND\g
J 0
(-2390 2310);
DISPLAY 0.659574 (-2390 2310);
PAINT MONO (-2390 2310);
DISPLAY INVISIBLE (-2390 2310);
FORCEPROP 1 LAST PATH I43
J 0
(-2325 2250);
DISPLAY 0.872340 (-2325 2250);
PAINT AQUA (-2325 2250);
DISPLAY INVISIBLE (-2325 2250);
FORCEPROP 1 LAST HDL_POWER GND
J 0
(-2400 2400);
DISPLAY 0.872340 (-2400 2400);
PAINT GREEN (-2400 2400);
DISPLAY INVISIBLE (-2400 2400);
FORCEPROP 1 LAST VOLTAGE 0.0V
J 0
(-2445 2207);
DISPLAY 0.340426 (-2445 2207);
PAINT SKYBLUE (-2445 2207);
DISPLAY INVISIBLE (-2445 2207);
FORCEPROP 2 LAST CDS_LIB mstr_symbols
J 0
(-2400 2250);
PAINT ORANGE (-2400 2250);
DISPLAY INVISIBLE (-2400 2250);
FORCEPROP 1 LAST SIZE 1B
J 0
(-2325 2200);
DISPLAY 0.872340 (-2325 2200);
PAINT AQUA (-2325 2200);
DISPLAY INVISIBLE (-2325 2200);
FORCEPROP 1 LAST BODY_TYPE PLUMBING
J 0
(-2445 2207);
DISPLAY 0.340426 (-2445 2207);
PAINT GREEN (-2445 2207);
DISPLAY INVISIBLE (-2445 2207);
FORCEADD P3V3_STBY..1
(-2400 3350);
FORCEPROP 3 LASTPIN (-2400 3300) SIG_NAME P3V3_STBY\g
J 0
(-2390 3310);
DISPLAY 0.659574 (-2390 3310);
PAINT MONO (-2390 3310);
DISPLAY INVISIBLE (-2390 3310);
FORCEPROP 2 LAST CDS_LIB mstr_symbols
J 0
(-2400 3350);
PAINT MONO (-2400 3350);
DISPLAY INVISIBLE (-2400 3350);
FORCEPROP 1 LAST PATH I45
J 0
(-2355 3352);
DISPLAY 0.340426 (-2355 3352);
PAINT GREEN (-2355 3352);
DISPLAY INVISIBLE (-2355 3352);
FORCEPROP 1 LAST HDL_POWER P3V3_STBY
J 0
(-2700 3225);
DISPLAY 0.872340 (-2700 3225);
PAINT ORANGE (-2700 3225);
DISPLAY INVISIBLE (-2700 3225);
FORCEPROP 1 LAST BODY_TYPE PLUMBING
J 0
(-2445 3307);
DISPLAY 0.340426 (-2445 3307);
PAINT GREEN (-2445 3307);
DISPLAY INVISIBLE (-2445 3307);
FORCEPROP 1 LAST VOLTAGE 3.3V
J 0
(-2445 3307);
DISPLAY 0.340426 (-2445 3307);
PAINT SKYBLUE (-2445 3307);
DISPLAY INVISIBLE (-2445 3307);
FORCEPROP 1 LAST SIZE 1B
J 0
(-2355 3372);
DISPLAY 0.340426 (-2355 3372);
PAINT GREEN (-2355 3372);
DISPLAY INVISIBLE (-2355 3372);
FORCEADD RES..2
(-2400 3150);
FORCEPROP 1 LAST LOCATION R7W3
J 0
(-2355 3275);
DISPLAY 0.617021 (-2355 3275);
PAINT AQUA (-2355 3275);
FORCEPROP 1 LAST VALUE 10.0K
J 0
(-2355 3225);
DISPLAY 0.617021 (-2355 3225);
PAINT SKYBLUE (-2355 3225);
FORCEPROP 1 LAST WATTAGE 1/16W
J 0
(-2360 3125);
DISPLAY 0.617021 (-2360 3125);
PAINT SKYBLUE (-2360 3125);
FORCEPROP 1 LAST MATERIAL EMPTY
J 0
(-2360 3075);
DISPLAY 0.617021 (-2360 3075);
PAINT RED (-2360 3075);
FORCEPROP 1 LASTPIN (-2400 3050) $PN 2
J 0
(-2395 3060);
DISPLAY 0.617021 (-2395 3060);
PAINT ORANGE (-2395 3060);
FORCEPROP 1 LASTPIN (-2400 3250) $PN 1
J 0
(-2395 3212);
DISPLAY 0.617021 (-2395 3212);
PAINT ORANGE (-2395 3212);
FORCEPROP 1 LAST TOLERANCE 1%
J 0
(-2355 3175);
DISPLAY 0.617021 (-2355 3175);
PAINT SKYBLUE (-2355 3175);
FORCEPROP 1 LAST PART_NUMBER G21796-016
J 0
(-2360 3025);
DISPLAY 0.617021 (-2360 3025);
PAINT BLUE (-2360 3025);
FORCEPROP 1 LAST PACK_TYPE 0402
J 0
(-2360 2975);
DISPLAY 0.617021 (-2360 2975);
PAINT SKYBLUE (-2360 2975);
FORCEPROP 1 LAST PATH I46
J 0
(-2350 3325);
DISPLAY 0.978723 (-2350 3325);
PAINT WHITE (-2350 3325);
DISPLAY INVISIBLE (-2350 3325);
FORCEPROP 2 LAST ROOM DB1200ZL
J 0
(-2350 3375);
DISPLAY 1.021277 (-2350 3375);
PAINT ORANGE (-2350 3375);
DISPLAY INVISIBLE (-2350 3375);
FORCEPROP 2 LAST SEC 1
J 0
(-2350 3375);
DISPLAY 0.680851 (-2350 3375);
PAINT MONO (-2350 3375);
DISPLAY INVISIBLE (-2350 3375);
FORCEPROP 2 LAST SEC_TYPE 0402
J 0
(-2350 3375);
DISPLAY 1.021277 (-2350 3375);
PAINT ORANGE (-2350 3375);
DISPLAY INVISIBLE (-2350 3375);
FORCEPROP 2 LAST BOM_COST SYS_CLOCK
J 0
(-2350 3475);
DISPLAY 1.021277 (-2350 3475);
PAINT ORANGE (-2350 3475);
DISPLAY INVISIBLE (-2350 3475);
FORCEPROP 2 LAST CDS_LIB mstr_discrete
J 0
(-2400 3150);
PAINT ORANGE (-2400 3150);
DISPLAY INVISIBLE (-2400 3150);
FORCEPROP 2 LAST CDS_LOCATION R7W3
J 0
(-2355 3275);
DISPLAY 0.617021 (-2355 3275);
PAINT AQUA (-2355 3275);
DISPLAY INVISIBLE (-2355 3275);
FORCEADD DESIGN_NOTE..1
(-5625 3625);
FORCEPROP 0 LAST L2 BMC PECI IS NOT USED
J 0
(-5825 3475);
DISPLAY 0.617021 (-5825 3475);
PAINT WHITE (-5825 3475);
FORCEPROP 0 LAST L1 PULL-UP FOR BMC IF
J 0
(-5825 3525);
DISPLAY 0.617021 (-5825 3525);
PAINT WHITE (-5825 3525);
FORCEPROP 1 LAST COMMENT_BODY TRUE
J 0
(-5600 3725);
DISPLAY 1.319149 (-5600 3725);
PAINT WHITE (-5600 3725);
DISPLAY INVISIBLE (-5600 3725);
FORCEPROP 2 LAST CDS_LIB mstr_symbols
J 0
(-5625 3625);
PAINT WHITE (-5625 3625);
DISPLAY INVISIBLE (-5625 3625);
FORCEADD DNS..2
(-2395 3145);
PAINT RED (-2395 3145);
FORCEPROP 1 LAST COMMENT_BODY TRUE
R 1
J 0
(-2320 2920);
DISPLAY 0.872340 (-2320 2920);
PAINT GREEN (-2320 2920);
DISPLAY INVISIBLE (-2320 2920);
FORCEPROP 2 LAST CDS_LIB mstr_misc
J 0
(-2395 3145);
PAINT ORANGE (-2395 3145);
DISPLAY INVISIBLE (-2395 3145);
FORCEADD DESIGN_NOTE..1
(-5250 2325);
FORCEPROP 0 LAST L1 PD STUFFED IN PECI_PCH
J 0
(-5450 2225);
DISPLAY 0.617021 (-5450 2225);
PAINT WHITE (-5450 2225);
FORCEPROP 0 LAST L2 EMPTY FOR BMC SKU OR NM DEBUG
J 0
(-5450 2175);
DISPLAY 0.617021 (-5450 2175);
PAINT WHITE (-5450 2175);
FORCEPROP 1 LAST COMMENT_BODY TRUE
J 0
(-5225 2425);
DISPLAY 1.319149 (-5225 2425);
PAINT WHITE (-5225 2425);
DISPLAY INVISIBLE (-5225 2425);
FORCEPROP 2 LAST CDS_LIB mstr_symbols
J 0
(-5250 2325);
PAINT WHITE (-5250 2325);
DISPLAY INVISIBLE (-5250 2325);
FORCEADD CAD_NOTE..1
(-3750 4050);
FORCEPROP 0 LAST L3 SO THAT THE PECI BUS STUB IS AS SHORT AS
J 0
(-3900 3850);
DISPLAY 0.617021 (-3900 3850);
PAINT WHITE (-3900 3850);
FORCEPROP 0 LAST L4 POSSIBLE WHEN ANY OF THEM IS UNSTUFFED
J 0
(-3900 3800);
DISPLAY 0.617021 (-3900 3800);
PAINT WHITE (-3900 3800);
FORCEPROP 0 LAST L1 AS CLOSE AS POSSIBLE TO THE COMMON NODE
J 0
(-3900 3950);
DISPLAY 0.617021 (-3900 3950);
PAINT WHITE (-3900 3950);
FORCEPROP 0 LAST L2 PLACE ALL 3 STUFFING OPTION RESISTORS
J 0
(-3900 3900);
DISPLAY 0.617021 (-3900 3900);
PAINT WHITE (-3900 3900);
FORCEPROP 1 LAST COMMENT_BODY TRUE
J 0
(-3725 4150);
DISPLAY 1.319149 (-3725 4150);
PAINT WHITE (-3725 4150);
DISPLAY INVISIBLE (-3725 4150);
FORCEPROP 2 LAST CDS_LIB mstr_symbols
J 0
(-3750 4050);
PAINT WHITE (-3750 4050);
DISPLAY INVISIBLE (-3750 4050);
FORCEADD INTEL_CORP_BPAGE..1
(0 0);
FORCEPROP 1 LAST CDS_CON_LAST_MODIFIED Fri Jun 16 17:49:01 2017
J 0
(-1425 325);
DISPLAY 1.361702 (-1425 325);
PAINT GREEN (-1425 325);
DISPLAY INVISIBLE (-1425 325);
FORCEPROP 1 LAST CUSTOM_TXT_CDS <CURRENT_DESIGN_SHEET> OF <TOTAL_DESIGN_SHEETS>
J 0
(-500 25);
PAINT ORANGE (-500 25);
FORCEPROP 1 LAST CUSTOM_TXT_CDS <CON_LAST_MODIFIED>
J 0
(-4000 100);
PAINT ORANGE (-4000 100);
FORCEPROP 2 LAST CUSTOM_TXT_CDS <XR_PAGE_TITLE>
J 0
(-7890 5250);
DISPLAY 0.638298 (-7890 5250);
PAINT PINK (-7890 5250);
DISPLAY INVISIBLE (-7890 5250);
FORCEPROP 1 LAST SCH_TITLE PECI
J 0
(-7950 50);
DISPLAY 1.212766 (-7950 50);
PAINT ORANGE (-7950 50);
FORCEPROP 2 LAST PAGE_BORDER TRUE
J 0
(-7890 5250);
DISPLAY 0.851064 (-7890 5250);
PAINT PINK (-7890 5250);
DISPLAY INVISIBLE (-7890 5250);
FORCEPROP 2 LAST CDS_LIB mstr_symbols
J 0
(0 0);
DISPLAY 1.361702 (0 0);
PAINT ORANGE (0 0);
DISPLAY INVISIBLE (0 0);
FORCEPROP 1 LAST COMMENT_BODY TRUE
J 0
(12 12);
DISPLAY 0.617021 (12 12);
PAINT GREEN (12 12);
DISPLAY INVISIBLE (12 12);
FORCEPROP 2 LAST CDS_XR_PAGE_TITLE CR-166 : @BASEBOARD_FAB2_LIB.BASEBOARD_FAB2(SCH_1):PAGE166
J 0
(-7890 5250);
DISPLAY 0.638298 (-7890 5250);
PAINT PINK (-7890 5250);
DISPLAY INVISIBLE (-7890 5250);
FORCEADD DNS..2
(-2395 2495);
PAINT RED (-2395 2495);
FORCEPROP 2 LAST CDS_LIB mstr_misc
J 0
(-2395 2495);
PAINT ORANGE (-2395 2495);
DISPLAY INVISIBLE (-2395 2495);
FORCEPROP 1 LAST COMMENT_BODY TRUE
R 1
J 0
(-2320 2270);
DISPLAY 0.872340 (-2320 2270);
PAINT GREEN (-2320 2270);
DISPLAY INVISIBLE (-2320 2270);
WIRE 16 -1 (-5050 3600)(-5050 3725);
WIRE 16 -1 (-4475 1950)(-4475 2050);
WIRE 16 -1 (-2725 3125)(-2725 3075);
WIRE 16 -1 (-2875 3425)(-2875 3375);
WIRE 16 -1 (-2875 2825)(-2875 3375);
WIRE 16 -1 (-2875 3375)(-2725 3375);
WIRE 16 -1 (-2725 3375)(-2725 3325);
WIRE 16 -1 (-2875 2825)(-3100 2825);
WIRE 16 -1 (-3700 2825)(-3800 2825);
WIRE 16 -1 (-2400 2400)(-2400 2300);
WIRE 16 -1 (-2400 3300)(-2400 3250);
WIRE 3 682 (-4900 2425)(-4900 2800);
WIRE 3 682 (-4675 2425)(-4900 2425);
WIRE 3 682 (-4900 2800)(-4675 2800);
WIRE 3 682 (-4675 2800)(-4675 2425);
WIRE 3 682 (-4675 3000)(-4900 3000);
WIRE 3 682 (-4675 3375)(-4675 3000);
WIRE 3 682 (-4900 3000)(-4900 3375);
WIRE 3 682 (-4900 3375)(-4675 3375);
WIRE 16 -1 (-4475 2525)(-5700 2525);
FORCEPROP 2 LAST SIG_NAME PECI_PCH
J 0
(-5630 2535);
DISPLAY 0.617021 (-5630 2535);
PAINT ORANGE (-5630 2535);
WIRE 16 -1 (-4475 2250)(-4475 2525);
WIRE 16 -1 (-4475 2525)(-4050 2525);
WIRE 16 -1 (-4050 2725)(-4050 2525);
WIRE 16 -1 (-3700 2725)(-4050 2725);
WIRE 3 682 (-3900 3600)(-3900 2050);
WIRE 3 682 (-1650 3600)(-3900 3600);
WIRE 3 682 (-3900 2050)(-1650 2050);
WIRE 3 682 (-1650 2050)(-1650 3600);
WIRE 16 -1 (-5050 3125)(-5700 3125);
FORCEPROP 2 LAST SIG_NAME PECI_BMC
J 0
(-5630 3135);
DISPLAY 0.617021 (-5630 3135);
PAINT ORANGE (-5630 3135);
WIRE 16 -1 (-5050 3400)(-5050 3125);
WIRE 16 -1 (-5050 3125)(-5050 2925);
WIRE 16 -1 (-5050 2925)(-3700 2925);
WIRE 16 -1 (-2400 2725)(-2400 2600);
WIRE 16 -1 (-2175 2725)(-2400 2725);
WIRE 16 -1 (-3100 2725)(-2400 2725);
FORCEPROP 2 LAST SIG_NAME PECI_CPU_G
J 0
(-2810 2735);
DISPLAY 0.617021 (-2810 2735);
PAINT ORANGE (-2810 2735);
WIRE 16 -1 (-2400 3050)(-2400 2925);
WIRE 16 -1 (-2400 2925)(-2175 2925);
WIRE 16 -1 (-3100 2925)(-2400 2925);
FORCEPROP 2 LAST SIG_NAME PECI_SEL
J 0
(-2810 2935);
DISPLAY 0.638298 (-2810 2935);
PAINT ORANGE (-2810 2935);
DOT 1 (-4475 2525);
DOT 1 (-2400 2925);
DOT 1 (-2400 2725);
DOT 1 (-2875 3375);
DOT 1 (-5050 3125);
FORCENOTE
ROOM=SM_CONTROLLER
(-7841 336) 0;
DISPLAY LEFT (-7841 336);
DISPLAY 0.617021 (-7841 336);
PAINT PURPLE (-7841 336);
FORCENOTE
TP FAB1 ADD SW 0311
(-3900 1975) 0;
DISPLAY LEFT (-3900 1975);
DISPLAY 1.021277 (-3900 1975);
PAINT RED (-3900 1975);
FORCENOTE
PUT C7W1 NEAR IC
(-2725 3450) 0;
DISPLAY LEFT (-2725 3450);
DISPLAY 1.021277 (-2725 3450);
PAINT PURPLE (-2725 3450);
FORCENOTE
TP FAB1 DEL SERIAL RES 0311
(-4925 3400) 0;
DISPLAY LEFT (-4925 3400);
DISPLAY 1.021277 (-4925 3400);
PAINT RED (-4925 3400);
FORCENOTE
PECI SEL = 1: S1, PIN1, BMC
(-3850 2500) 0;
DISPLAY LEFT (-3850 2500);
DISPLAY 1.021277 (-3850 2500);
PAINT PURPLE (-3850 2500);
FORCENOTE
PECI SEL = 0: S0, PIN3, PCH (DEFAULT)
(-3850 2550) 0;
DISPLAY LEFT (-3850 2550);
DISPLAY 1.021277 (-3850 2550);
PAINT PURPLE (-3850 2550);
FORCENOTE
TP FAB1 DEL PU AND SERIAL RES 0311
(-4950 2350) 0;
DISPLAY LEFT (-4950 2350);
DISPLAY 1.021277 (-4950 2350);
PAINT RED (-4950 2350);
QUIT
